# scalenode-cm4-baseboard — assets/stackup.csv
Name;Type;Material;Thickness[mm];Constant
F.Mask;Top Solder Mask;;0.02;
F.Cu;copper;;0.018;
dielectric 1;prepreg;FR4;0.12;4.2
In1.Cu;copper;;0.035;
dielectric 2;core;FR4;1.2;4.2
In2.Cu;copper;;0.035;
dielectric 3;prepreg;FR4;0.12;4.2
B.Cu;copper;;0.018;
B.Mask;Bottom Solder Mask;;0.02;
